# Stackup_F0T_PDB_GPU_10L_2p36mm_IT-170GT_RTF_Rev0p2_20211201.xls — Manufacuring violation (pcb-stackup)
| Description | Quanta layout design rule | The stackup design rule |  |
| Min. Innerlayer Line Width, 0.5 oz copper (mil) | 3 | NA | Normal |
| Min. Innerlayer Space, 0.5 oz copper (mil) | 3.5 | NA | Medium |
| Min. Innerlayer Line Width,   1 oz copper (mil) | 4 | 4 | High |
| Min. Innerlayer Space, 1 oz copper (mil) | 4 | NA |  |
| Min. Innerlayer Line Width,   2oz copper (mil) | 6 | NA |  |
| Min. Innerlayer Space,  2oz copper (mil) | 6 | NA |  |
| Min. Outerlayer line width, 0.5oz copper foil (mil) | 3.5 | 4 |  |
| Min. Outerlayer Space, 0.5oz copper foil (mil) | 3.5 | NA |  |
| Min. Inner Core/PP thickness (mil) | 3 | 6 |  |
| Max. Aspect Ratio for min. DHS | 12.24 | 9.48 |  |
